# T6G (Grand Teton) — schematic netlist excerpt (pin names and nets, part order shuffled) for the footprints in the layout excerpt that follows; sources: Cadence DE-HDL packaged netlist, KiCad conversion of 04192023_DAF0TMB3IC0_F0TG_MB_C_brd_V02_OCP.brd

J33  SCONN288_DDR506112002KQ  IO  pkg DDR288S_1-1VXC  page 103
  VIN_BULK0  = P12V_MEM_CPU1
  RFU0  = NC
  VIN_MGMT  = P3V3_AUX
  HSCL  = I3C_SPD_DDRF_CPU1_SCL
  HSDA  = I3C_SPD_DDRF_CPU1_SDA
  VSS0  = GND
  DQ0_A  = M_F_CPU1_SA_DQ<0>
  VSS1  = GND
  DQ1_A  = M_F_CPU1_SA_DQ<1>
  VSS2  = GND
  DQS0_A_T  = M_F_CPU1_SA_DQS_DP<0>
  DQS0_A_C  = M_F_CPU1_SA_DQS_DN<0>
  VSS3  = GND
  DQ4_A  = M_F_CPU1_SA_DQ<4>
  VSS4  = GND
  DQ5_A  = M_F_CPU1_SA_DQ<5>
  VSS5  = GND
  DQ8_A  = M_F_CPU1_SA_DQ<8>
  VSS6  = GND
  DQ9_A  = M_F_CPU1_SA_DQ<9>
  VSS7  = GND
  DQS1_A_T  = M_F_CPU1_SA_DQS_DP<1>
  DQS1_A_C  = M_F_CPU1_SA_DQS_DN<1>
  VSS8  = GND
  DQ12_A  = M_F_CPU1_SA_DQ<12>
  VSS9  = GND
  DQ13_A  = M_F_CPU1_SA_DQ<13>
  VSS10  = GND
  DQ16_A  = M_F_CPU1_SA_DQ<16>
  VSS11  = GND
  DQ17_A  = M_F_CPU1_SA_DQ<17>
  VSS12  = GND
  DQS2_A_T  = M_F_CPU1_SA_DQS_DP<2>
  DQS2_A_C  = M_F_CPU1_SA_DQS_DN<2>
  VSS13  = GND
  DQ20_A  = M_F_CPU1_SA_DQ<20>
  VSS14  = GND
  DQ21_A  = M_F_CPU1_SA_DQ<21>
  VSS15  = GND
  DQ24_A  = M_F_CPU1_SA_DQ<24>
  VSS16  = GND
  DQ25_A  = M_F_CPU1_SA_DQ<25>
  VSS17  = GND
  DQS3_A_T  = M_F_CPU1_SA_DQS_DP<3>
  DQS3_A_C  = M_F_CPU1_SA_DQS_DN<3>
  VSS18  = GND
  DQ28_A  = M_F_CPU1_SA_DQ<28>
  VSS19  = GND
  DQ29_A  = M_F_CPU1_SA_DQ<29>
  VSS20  = GND
  CB0_A  = M_F_CPU1_SA_CB<0>
  VSS21  = GND
  CB1_A  = M_F_CPU1_SA_CB<1>
  VSS22  = GND
  DQS4_A_T  = M_F_CPU1_SA_DQS_DP<4>
  DQS4_A_C  = M_F_CPU1_SA_DQS_DN<4>
  VSS23  = GND
  CB4_A  = M_F_CPU1_SA_CB<4>
  VSS24  = GND
  CB5_A  = M_F_CPU1_SA_CB<5>
  VSS25  = GND
  ALERT_N  = M_F_CPU1_ALERT_N
  VSS26  = GND
  CS0_A_N  = M_F_CPU1_SA_CS_N<0>
  VSS27  = GND
  CA0_A  = M_F_CPU1_SA_CA<0>
  VSS28  = GND
  CA2_A  = M_F_CPU1_SA_CA<2>
  VSS29  = GND
  CA4_A  = M_F_CPU1_SA_CA<4>
  VSS30  = GND
  CA6_A  = M_F_CPU1_SA_CA<6>
  VSS31  = GND
  PAR_A  = M_F_CPU1_SA_PAR
  VSS32  = GND
  CA0_B  = M_F_CPU1_SB_CA<0>
  VSS33  = GND
  CA2_B  = M_F_CPU1_SB_CA<2>
  VSS34  = GND
  CA4_B  = M_F_CPU1_SB_CA<4>
  VSS35  = GND
  CA6_B  = M_F_CPU1_SB_CA<6>
  VSS36  = GND
  CS0_B_N  = M_F_CPU1_SB_CS_N<0>
  VSS37  = GND
  \lbd||rsp_a_n\  = M_F_CPU1_SA_RSP<0>
  \lbs||rsp_b_n\  = M_F_CPU1_SB_RSP<0>
  VSS38  = GND
  CB4_B  = M_F_CPU1_SB_CB<4>
  VSS39  = GND
  CB5_B  = M_F_CPU1_SB_CB<5>
  VSS40  = GND
  \dqs9_b_t||tdqs9_b_t||dbi4_b_n\  = M_F_CPU1_SB_DQS_DP<9>
  \dqs9_b_c||tdqs9_b_c\  = M_F_CPU1_SB_DQS_DN<9>
  VSS41  = GND
  CB0_B  = M_F_CPU1_SB_CB<0>
  VSS42  = GND
  CB1_B  = M_F_CPU1_SB_CB<1>
  VSS43  = GND
  DQ0_B  = M_F_CPU1_SB_DQ<0>
  VSS44  = GND
  DQ1_B  = M_F_CPU1_SB_DQ<1>
  VSS45  = GND
  DQS0_B_T  = M_F_CPU1_SB_DQS_DP<0>
  DQS0_B_C  = M_F_CPU1_SB_DQS_DN<0>
  VSS46  = GND
  DQ4_B  = M_F_CPU1_SB_DQ<4>
  VSS47  = GND
  DQ5_B  = M_F_CPU1_SB_DQ<5>
  VSS48  = GND
  DQ8_B  = M_F_CPU1_SB_DQ<8>
  VSS49  = GND
  DQ9_B  = M_F_CPU1_SB_DQ<9>
  VSS50  = GND
  DQS1_B_T  = M_F_CPU1_SB_DQS_DP<1>
  DQS1_B_C  = M_F_CPU1_SB_DQS_DN<1>
  VSS51  = GND
  DQ12_B  = M_F_CPU1_SB_DQ<12>
  VSS52  = GND
  DQ13_B  = M_F_CPU1_SB_DQ<13>
  VSS53  = GND
  DQ16_B  = M_F_CPU1_SB_DQ<16>
  VSS54  = GND
  DQ17_B  = M_F_CPU1_SB_DQ<17>
  VSS55  = GND
  DQS2_B_T  = M_F_CPU1_SB_DQS_DP<2>
  DQS2_B_C  = M_F_CPU1_SB_DQS_DN<2>
  VSS56  = GND
  DQ20_B  = M_F_CPU1_SB_DQ<20>
  VSS57  = GND
  DQ21_B  = M_F_CPU1_SB_DQ<21>
  VSS58  = GND
  DQ24_B  = M_F_CPU1_SB_DQ<24>
  VSS59  = GND
  DQ25_B  = M_F_CPU1_SB_DQ<25>
  VSS60  = GND
  DQS3_B_T  = M_F_CPU1_SB_DQS_DP<3>
  DQS3_B_C  = M_F_CPU1_SB_DQS_DN<3>
  VSS61  = GND
  DQ28_B  = M_F_CPU1_SB_DQ<28>
  VSS62  = GND
  DQ29_B  = M_F_CPU1_SB_DQ<29>
  VSS63  = GND
  RFU1  = NC
  VIN_BULK1  = P12V_MEM_CPU1
  VIN_BULK2  = P12V_MEM_CPU1
  \pwr_good||fail_n\  = PWRGD_CHF_CPU1_DIMM
  HAS  = PD_CHF_CPU1_DIMM_SAA
  RFU2  = NC
  RFU3  = NC
  VSS64  = GND
  DQ2_A  = M_F_CPU1_SA_DQ<2>
  VSS65  = GND
  DQ3_A  = M_F_CPU1_SA_DQ<3>
  VSS66  = GND
  \dqs5_a_c||tdqs5_a_c||dqs5_a_t||tdqs5_a_t\  = M_F_CPU1_SA_DQS_DN<5>
  \dqs5_a_t||tdqs5_a_t\  = M_F_CPU1_SA_DQS_DP<5>
  VSS67  = GND
  DQ6_A  = M_F_CPU1_SA_DQ<6>
  VSS68  = GND
  DQ7_A  = M_F_CPU1_SA_DQ<7>
  VSS69  = GND
  DQ10_A  = M_F_CPU1_SA_DQ<10>
  VSS70  = GND
  DQ11_A  = M_F_CPU1_SA_DQ<11>
  VSS71  = GND
  \dqs6_a_c||tdqs6_a_c||dqs6_a_t||tdqs6_a_t\  = M_F_CPU1_SA_DQS_DN<6>
  \dqs6_a_t||tdqs6_a_t\  = M_F_CPU1_SA_DQS_DP<6>
  VSS72  = GND
  DQ14_A  = M_F_CPU1_SA_DQ<14>
  VSS73  = GND
  DQ15_A  = M_F_CPU1_SA_DQ<15>
  VSS74  = GND
  DQ18_A  = M_F_CPU1_SA_DQ<18>
  VSS75  = GND
  DQ19_A  = M_F_CPU1_SA_DQ<19>
  VSS76  = GND
  \dqs7_a_c||tdqs7_a_c\  = M_F_CPU1_SA_DQS_DN<7>
  \dqs7_a_t||tdqs7_a_t\  = M_F_CPU1_SA_DQS_DP<7>
  VSS77  = GND
  DQ22_A  = M_F_CPU1_SA_DQ<22>
  VSS78  = GND
  DQ23_A  = M_F_CPU1_SA_DQ<23>
  VSS79  = GND
  DQ26_A  = M_F_CPU1_SA_DQ<26>
  VSS80  = GND
  DQ27_A  = M_F_CPU1_SA_DQ<27>
  VSS81  = GND
  \dqs8_a_c||tdqs8_a_c\  = M_F_CPU1_SA_DQS_DN<8>
  \dqs8_a_t||tdqs8_a_t\  = M_F_CPU1_SA_DQS_DP<8>
  VSS82  = GND
  DQ30_A  = M_F_CPU1_SA_DQ<30>
  VSS83  = GND
  DQ31_A  = M_F_CPU1_SA_DQ<31>
  VSS84  = GND
  CB2_A  = M_F_CPU1_SA_CB<2>
  VSS85  = GND
  CB3_A  = M_F_CPU1_SA_CB<3>
  VSS86  = GND
  \dqs9_a_c||tdqs9_a_c\  = M_F_CPU1_SA_DQS_DN<9>
  \dqs9_a_t||tdqs9_a_t\  = M_F_CPU1_SA_DQS_DP<9>
  VSS87  = GND
  CB6_A  = M_F_CPU1_SA_CB<6>
  VSS88  = GND
  CB7_A  = M_F_CPU1_SA_CB<7>
  VSS89  = GND
  RESET_N  = M_F_CPU1_RESET_N
  VSS90  = GND
  CS1_A_N  = M_F_CPU1_SA_CS_N<1>
  VSS91  = GND
  CA1_A  = M_F_CPU1_SA_CA<1>
  VSS92  = GND
  CA3_A  = M_F_CPU1_SA_CA<3>
  VSS93  = GND
  CA5_A  = M_F_CPU1_SA_CA<5>
  VSS94  = GND
  CK_T  = M_F_CPU1_CLK_DP<0>
  CK_C  = M_F_CPU1_CLK_DN<0>
  VSS95  = GND
  RFU4  = NC
  CA1_B  = M_F_CPU1_SB_CA<1>
  VSS96  = GND
  CA3_B  = M_F_CPU1_SB_CA<3>
  VSS97  = GND
  CA5_B  = M_F_CPU1_SB_CA<5>
  VSS98  = GND
  PAR_B  = M_F_CPU1_SB_PAR
  VSS99  = GND
  CS1_B_N  = M_F_CPU1_SB_CS_N<1>
  VSS100  = GND
  RFU5  = NC
  RFU6  = NC
  VSS101  = GND
  CB6_B  = M_F_CPU1_SB_CB<6>
  VSS102  = GND
  CB7_B  = M_F_CPU1_SB_CB<7>
  VSS103  = GND
  DQS4_B_C  = M_F_CPU1_SB_DQS_DN<4>
  DQS4_B_T  = M_F_CPU1_SB_DQS_DP<4>
  VSS104  = GND
  CB2_B  = M_F_CPU1_SB_CB<2>
  VSS105  = GND
  CB3_B  = M_F_CPU1_SB_CB<3>
  VSS106  = GND
  DQ2_B  = M_F_CPU1_SB_DQ<2>
  VSS107  = GND
  DQ3_B  = M_F_CPU1_SB_DQ<3>
  VSS108  = GND
  \dqs5_b_c||tdqs5_b_c\  = M_F_CPU1_SB_DQS_DN<5>
  \dqs5_b_t||tdqs5_b_t\  = M_F_CPU1_SB_DQS_DP<5>
  VSS109  = GND
  DQ6_B  = M_F_CPU1_SB_DQ<6>
  VSS110  = GND
  DQ7_B  = M_F_CPU1_SB_DQ<7>
  VSS111  = GND
  DQ10_B  = M_F_CPU1_SB_DQ<10>
  VSS112  = GND
  DQ11_B  = M_F_CPU1_SB_DQ<11>
  VSS113  = GND
  \dqs6_b_c||tdqs6_b_c\  = M_F_CPU1_SB_DQS_DN<6>
  \dqs6_b_t||tdqs6_b_t\  = M_F_CPU1_SB_DQS_DP<6>
  VSS114  = GND
  DQ14_B  = M_F_CPU1_SB_DQ<14>
  VSS115  = GND
  DQ15_B  = M_F_CPU1_SB_DQ<15>
  VSS116  = GND
  DQ18_B  = M_F_CPU1_SB_DQ<18>
  VSS117  = GND
  DQ19_B  = M_F_CPU1_SB_DQ<19>
  VSS118  = GND
  \dqs7_b_c||tdqs7_b_c\  = M_F_CPU1_SB_DQS_DN<7>
  \dqs7_b_t||tdqs7_b_t\  = M_F_CPU1_SB_DQS_DP<7>
  VSS119  = GND
  DQ22_B  = M_F_CPU1_SB_DQ<22>
  VSS120  = GND
  DQ23_B  = M_F_CPU1_SB_DQ<23>
  VSS121  = GND
  DQ26_B  = M_F_CPU1_SB_DQ<26>
  VSS122  = GND
  DQ27_B  = M_F_CPU1_SB_DQ<27>
  VSS123  = GND
  \dqs8_b_c||tdqs8_b_c\  = M_F_CPU1_SB_DQS_DN<8>
  \dqs8_b_t||tdqs8_b_t\  = M_F_CPU1_SB_DQS_DP<8>
  VSS124  = GND
  DQ30_B  = M_F_CPU1_SB_DQ<30>
  VSS125  = GND
  DQ31_B  = M_F_CPU1_SB_DQ<31>
  VSS126  = GND
  G1  = GND
  G2  = GND
  G3  = GND

(kicad_pcb
	(version 20260206)
	(generator "pcbnew")
	(generator_version "10.0")
	(general
		(thickness 1.6)
		(legacy_teardrops no)
	)
	(paper "A4")
	(title_block
		(title "04192023_DAF0TMB3IC0_F0TG_MB_C_brd_V02_OCP.brd")
		(comment 1 "Grand Teton / footprint 4248 of 8354 (J33), pads 231-276 of 291")
	)
	(layers
		(0 "F.Cu" signal "TOP")
		(4 "In1.Cu" signal "GND")
		(6 "In2.Cu" signal "IN1")
		(8 "In3.Cu" signal "GND1")
		(10 "In4.Cu" signal "IN2")
		(12 "In5.Cu" signal "GND2")
		(14 "In6.Cu" signal "IN3")
		(16 "In7.Cu" signal "GND3")
		(18 "In8.Cu" signal "VCC")
		(20 "In9.Cu" signal "VCC1")
		(22 "In10.Cu" signal "GND4")
		(24 "In11.Cu" signal "IN4")
		(26 "In12.Cu" signal "GND5")
		(28 "In13.Cu" signal "IN5")
		(30 "In14.Cu" signal "GND6")
		(32 "In15.Cu" signal "IN6")
		(34 "In16.Cu" signal "GND7")
		(2 "B.Cu" signal "BOTTOM")
		(9 "F.Adhes" user "F.Adhesive")
		(11 "B.Adhes" user "B.Adhesive")
		(13 "F.Paste" user "Package Geometry/Pastemask Top")
		(15 "B.Paste" user "Package Geometry/Pastemask Bottom")
		(5 "F.SilkS" user "Ref Des/Silkscreen Top")
		(7 "B.SilkS" user "Ref Des/Silkscreen Bottom")
		(1 "F.Mask" user "Board Geometry/Soldermask Top")
		(3 "B.Mask" user "Board Geometry/Soldermask Bottom")
		(17 "Dwgs.User" user "User.Drawings")
		(19 "Cmts.User" user "User.Comments")
		(21 "Eco1.User" user "User.Eco1")
		(23 "Eco2.User" user "User.Eco2")
		(25 "Edge.Cuts" user "Board Geometry/Outline")
		(27 "Margin" user)
		(31 "F.CrtYd" user "Package Geometry/Place Bound Top")
		(29 "B.CrtYd" user "Package Geometry/Place Bound Bottom")
		(35 "F.Fab" user "Ref Des/Assembly Top")
		(33 "B.Fab" user "Ref Des/Assembly Bottom")
	)
	(footprint ""
		(layer "F.Cu")
		(at 19.658076 -255.560322 180)
		(property "Reference" "J33"
			(at -1.25984 -82.079846 0)
			(unlocked yes)
			(layer "F.SilkS")
			(effects
				(font
					(size 0.7874 0.5842)
					(thickness 0.1524)
				)
			)
		)
		(property "Value" ""
			(at 0 0 180)
			(layer "F.Fab")
			(effects
				(font
					(size 1.27 1.27)
				)
			)
		)
		(duplicate_pad_numbers_are_jumpers no)
		(pad "231" smd rect
			(at 2.050034 14.875002 90)
			(size 0.519938 1.4986)
			(layers "F.Cu" "F.Mask" "F.Paste")
			(net "Net_2331")
		)
		(pad "232" smd rect
			(at 2.050034 15.724886 90)
			(size 0.519938 1.4986)
			(layers "F.Cu" "F.Mask" "F.Paste")
			(net "Net_2332")
		)
		(pad "233" smd rect
			(at 2.050034 16.575024 90)
			(size 0.519938 1.4986)
			(layers "F.Cu" "F.Mask" "F.Paste")
			(net "GND")
		)
		(pad "234" smd rect
			(at 2.050034 17.424908 90)
			(size 0.519938 1.4986)
			(layers "F.Cu" "F.Mask" "F.Paste")
			(net "M_F_CPU1_SB_CB<6>")
		)
		(pad "235" smd rect
			(at 2.050034 18.275046 90)
			(size 0.519938 1.4986)
			(layers "F.Cu" "F.Mask" "F.Paste")
			(net "GND")
		)
		(pad "236" smd rect
			(at 2.050034 19.12493 90)
			(size 0.519938 1.4986)
			(layers "F.Cu" "F.Mask" "F.Paste")
			(net "M_F_CPU1_SB_CB<7>")
		)
		(pad "237" smd rect
			(at 2.050034 19.975068 90)
			(size 0.519938 1.4986)
			(layers "F.Cu" "F.Mask" "F.Paste")
			(net "GND")
		)
		(pad "238" smd rect
			(at 2.050034 20.824952 90)
			(size 0.519938 1.4986)
			(layers "F.Cu" "F.Mask" "F.Paste")
			(net "M_F_CPU1_SB_DQS_DN<4>")
		)
		(pad "239" smd rect
			(at 2.050034 21.67509 90)
			(size 0.519938 1.4986)
			(layers "F.Cu" "F.Mask" "F.Paste")
			(net "M_F_CPU1_SB_DQS_DP<4>")
		)
		(pad "240" smd rect
			(at 2.050034 22.524974 90)
			(size 0.519938 1.4986)
			(layers "F.Cu" "F.Mask" "F.Paste")
			(net "GND")
		)
		(pad "241" smd rect
			(at 2.050034 23.375112 90)
			(size 0.519938 1.4986)
			(layers "F.Cu" "F.Mask" "F.Paste")
			(net "M_F_CPU1_SB_CB<2>")
		)
		(pad "242" smd rect
			(at 2.050034 24.224996 90)
			(size 0.519938 1.4986)
			(layers "F.Cu" "F.Mask" "F.Paste")
			(net "GND")
		)
		(pad "243" smd rect
			(at 2.050034 25.07488 90)
			(size 0.519938 1.4986)
			(layers "F.Cu" "F.Mask" "F.Paste")
			(net "M_F_CPU1_SB_CB<3>")
		)
		(pad "244" smd rect
			(at 2.050034 25.925018 90)
			(size 0.519938 1.4986)
			(layers "F.Cu" "F.Mask" "F.Paste")
			(net "GND")
		)
		(pad "245" smd rect
			(at 2.050034 26.774902 90)
			(size 0.519938 1.4986)
			(layers "F.Cu" "F.Mask" "F.Paste")
			(net "M_F_CPU1_SB_DQ<2>")
		)
		(pad "246" smd rect
			(at 2.050034 27.62504 90)
			(size 0.519938 1.4986)
			(layers "F.Cu" "F.Mask" "F.Paste")
			(net "GND")
		)
		(pad "247" smd rect
			(at 2.050034 28.474924 90)
			(size 0.519938 1.4986)
			(layers "F.Cu" "F.Mask" "F.Paste")
			(net "M_F_CPU1_SB_DQ<3>")
		)
		(pad "248" smd rect
			(at 2.050034 29.325062 90)
			(size 0.519938 1.4986)
			(layers "F.Cu" "F.Mask" "F.Paste")
			(net "GND")
		)
		(pad "249" smd rect
			(at 2.050034 30.174946 90)
			(size 0.519938 1.4986)
			(layers "F.Cu" "F.Mask" "F.Paste")
			(net "M_F_CPU1_SB_DQS_DN<5>")
		)
		(pad "250" smd rect
			(at 2.050034 31.025084 90)
			(size 0.519938 1.4986)
			(layers "F.Cu" "F.Mask" "F.Paste")
			(net "M_F_CPU1_SB_DQS_DP<5>")
		)
		(pad "251" smd rect
			(at 2.050034 31.874968 90)
			(size 0.519938 1.4986)
			(layers "F.Cu" "F.Mask" "F.Paste")
			(net "GND")
		)
		(pad "252" smd rect
			(at 2.050034 32.725106 90)
			(size 0.519938 1.4986)
			(layers "F.Cu" "F.Mask" "F.Paste")
			(net "M_F_CPU1_SB_DQ<6>")
		)
		(pad "253" smd rect
			(at 2.050034 33.57499 90)
			(size 0.519938 1.4986)
			(layers "F.Cu" "F.Mask" "F.Paste")
			(net "GND")
		)
		(pad "254" smd rect
			(at 2.050034 34.425128 90)
			(size 0.519938 1.4986)
			(layers "F.Cu" "F.Mask" "F.Paste")
			(net "M_F_CPU1_SB_DQ<7>")
		)
		(pad "255" smd rect
			(at 2.050034 35.275012 90)
			(size 0.519938 1.4986)
			(layers "F.Cu" "F.Mask" "F.Paste")
			(net "GND")
		)
		(pad "256" smd rect
			(at 2.050034 36.124896 90)
			(size 0.519938 1.4986)
			(layers "F.Cu" "F.Mask" "F.Paste")
			(net "M_F_CPU1_SB_DQ<10>")
		)
		(pad "257" smd rect
			(at 2.050034 36.975034 90)
			(size 0.519938 1.4986)
			(layers "F.Cu" "F.Mask" "F.Paste")
			(net "GND")
		)
		(pad "258" smd rect
			(at 2.050034 37.824918 90)
			(size 0.519938 1.4986)
			(layers "F.Cu" "F.Mask" "F.Paste")
			(net "M_F_CPU1_SB_DQ<11>")
		)
		(pad "259" smd rect
			(at 2.050034 38.675056 90)
			(size 0.519938 1.4986)
			(layers "F.Cu" "F.Mask" "F.Paste")
			(net "GND")
		)
		(pad "260" smd rect
			(at 2.050034 39.52494 90)
			(size 0.519938 1.4986)
			(layers "F.Cu" "F.Mask" "F.Paste")
			(net "M_F_CPU1_SB_DQS_DN<6>")
		)
		(pad "261" smd rect
			(at 2.050034 40.375078 90)
			(size 0.519938 1.4986)
			(layers "F.Cu" "F.Mask" "F.Paste")
			(net "M_F_CPU1_SB_DQS_DP<6>")
		)
		(pad "262" smd rect
			(at 2.050034 41.224962 90)
			(size 0.519938 1.4986)
			(layers "F.Cu" "F.Mask" "F.Paste")
			(net "GND")
		)
		(pad "263" smd rect
			(at 2.050034 42.0751 90)
			(size 0.519938 1.4986)
			(layers "F.Cu" "F.Mask" "F.Paste")
			(net "M_F_CPU1_SB_DQ<14>")
		)
		(pad "264" smd rect
			(at 2.050034 42.924984 90)
			(size 0.519938 1.4986)
			(layers "F.Cu" "F.Mask" "F.Paste")
			(net "GND")
		)
		(pad "265" smd rect
			(at 2.050034 43.775122 90)
			(size 0.519938 1.4986)
			(layers "F.Cu" "F.Mask" "F.Paste")
			(net "M_F_CPU1_SB_DQ<15>")
		)
		(pad "266" smd rect
			(at 2.050034 44.625006 90)
			(size 0.519938 1.4986)
			(layers "F.Cu" "F.Mask" "F.Paste")
			(net "GND")
		)
		(pad "267" smd rect
			(at 2.050034 45.47489 90)
			(size 0.519938 1.4986)
			(layers "F.Cu" "F.Mask" "F.Paste")
			(net "M_F_CPU1_SB_DQ<18>")
		)
		(pad "268" smd rect
			(at 2.050034 46.325028 90)
			(size 0.519938 1.4986)
			(layers "F.Cu" "F.Mask" "F.Paste")
			(net "GND")
		)
		(pad "269" smd rect
			(at 2.050034 47.174912 90)
			(size 0.519938 1.4986)
			(layers "F.Cu" "F.Mask" "F.Paste")
			(net "M_F_CPU1_SB_DQ<19>")
		)
		(pad "270" smd rect
			(at 2.050034 48.02505 90)
			(size 0.519938 1.4986)
			(layers "F.Cu" "F.Mask" "F.Paste")
			(net "GND")
		)
		(pad "271" smd rect
			(at 2.050034 48.874934 90)
			(size 0.519938 1.4986)
			(layers "F.Cu" "F.Mask" "F.Paste")
			(net "M_F_CPU1_SB_DQS_DN<7>")
		)
		(pad "272" smd rect
			(at 2.050034 49.725072 90)
			(size 0.519938 1.4986)
			(layers "F.Cu" "F.Mask" "F.Paste")
			(net "M_F_CPU1_SB_DQS_DP<7>")
		)
		(pad "273" smd rect
			(at 2.050034 50.574956 90)
			(size 0.519938 1.4986)
			(layers "F.Cu" "F.Mask" "F.Paste")
			(net "GND")
		)
		(pad "274" smd rect
			(at 2.050034 51.425094 90)
			(size 0.519938 1.4986)
			(layers "F.Cu" "F.Mask" "F.Paste")
			(net "M_F_CPU1_SB_DQ<22>")
		)
		(pad "275" smd rect
			(at 2.050034 52.274978 90)
			(size 0.519938 1.4986)
			(layers "F.Cu" "F.Mask" "F.Paste")
			(net "GND")
		)
		(pad "276" smd rect
			(at 2.050034 53.125116 90)
			(size 0.519938 1.4986)
			(layers "F.Cu" "F.Mask" "F.Paste")
			(net "M_F_CPU1_SB_DQ<23>")
		)
	)
)
